# S9S_MB_2U (Grand Teton) — schematic netlist excerpt (pin names and nets, part order shuffled) for the footprints in the layout excerpt that follows; sources: Cadence DE-HDL packaged netlist, KiCad conversion of 03242023_DA0F0TMBIJ0_F0T_Motherboard_J_brd_V01_OCP.brd

PC310_P0_1  Q_CAP  1UF 16V 10% X6S  pkg C0402  page 267 : A = PVCCIN_CPU0 ; B = GND
C1259  Q_CAP  47UF 4V 20% X6S  pkg C0805  page 189 : A = P1V8_PCH_PLL_AUX ; B = GND
PC2341  Q_CAP  560PF 50V 10% X7R  pkg C0402  page 193 : A = P12V_E1S_ISET_0_R ; B = GND

(kicad_pcb
	(version 20260206)
	(generator "pcbnew")
	(generator_version "10.0")
	(general
		(thickness 1.6)
		(legacy_teardrops no)
	)
	(paper "A4")
	(title_block
		(title "03242023_DA0F0TMBIJ0_F0T_Motherboard_J_brd_V01_OCP.brd")
		(comment 1 "Grand Teton / footprints 4891-4893 of 6105")
	)
	(layers
		(0 "F.Cu" signal "TOP")
		(4 "In1.Cu" signal "GND")
		(6 "In2.Cu" signal "IN1")
		(8 "In3.Cu" signal "GND1")
		(10 "In4.Cu" signal "IN2")
		(12 "In5.Cu" signal "GND2")
		(14 "In6.Cu" signal "IN3")
		(16 "In7.Cu" signal "GND3")
		(18 "In8.Cu" signal "VCC")
		(20 "In9.Cu" signal "VCC1")
		(22 "In10.Cu" signal "GND4")
		(24 "In11.Cu" signal "IN4")
		(26 "In12.Cu" signal "GND5")
		(28 "In13.Cu" signal "IN5")
		(30 "In14.Cu" signal "GND6")
		(32 "In15.Cu" signal "IN6")
		(34 "In16.Cu" signal "GND7")
		(2 "B.Cu" signal "BOTTOM")
		(9 "F.Adhes" user "F.Adhesive")
		(11 "B.Adhes" user "B.Adhesive")
		(13 "F.Paste" user "Package Geometry/Pastemask Top")
		(15 "B.Paste" user "Package Geometry/Pastemask Bottom")
		(5 "F.SilkS" user "Ref Des/Silkscreen Top")
		(7 "B.SilkS" user "Ref Des/Silkscreen Bottom")
		(1 "F.Mask" user "Board Geometry/Soldermask Top")
		(3 "B.Mask" user "Board Geometry/Soldermask Bottom")
		(17 "Dwgs.User" user "User.Drawings")
		(19 "Cmts.User" user "User.Comments")
		(21 "Eco1.User" user "User.Eco1")
		(23 "Eco2.User" user "User.Eco2")
		(25 "Edge.Cuts" user "Board Geometry/Outline")
		(27 "Margin" user)
		(31 "F.CrtYd" user "Package Geometry/Place Bound Top")
		(29 "B.CrtYd" user "Package Geometry/Place Bound Bottom")
		(35 "F.Fab" user "Ref Des/Assembly Top")
		(33 "B.Fab" user "Ref Des/Assembly Bottom")
	)
	(footprint ""
		(layer "B.Cu")
		(at 352.097848 -54.435756 90)
		(property "Reference" "C1259"
			(at 0 0 90)
			(layer "B.SilkS")
			(hide yes)
			(effects
				(font
					(size 1.27 1.27)
				)
				(justify mirror)
			)
		)
		(property "Value" ""
			(at 0 0 90)
			(layer "B.Fab")
			(effects
				(font
					(size 1.27 1.27)
				)
				(justify mirror)
			)
		)
		(duplicate_pad_numbers_are_jumpers no)
		(fp_line
			(start 1.524 -0.762)
			(end -1.524 -0.762)
			(stroke
				(width 0.1524)
				(type default)
			)
			(layer "B.SilkS")
		)
		(fp_line
			(start -1.524 -0.762)
			(end -1.524 0.762)
			(stroke
				(width 0.1524)
				(type default)
			)
			(layer "B.SilkS")
		)
		(fp_line
			(start 1.524 0.762)
			(end 1.524 -0.762)
			(stroke
				(width 0.1524)
				(type default)
			)
			(layer "B.SilkS")
		)
		(fp_line
			(start -1.524 0.762)
			(end 1.524 0.762)
			(stroke
				(width 0.1524)
				(type default)
			)
			(layer "B.SilkS")
		)
		(fp_line
			(start 1.1049 -0.724916)
			(end 1.1049 0.724916)
			(stroke
				(width 0.1)
				(type default)
			)
			(layer "B.Fab")
		)
		(fp_line
			(start -1.1049 -0.724916)
			(end 1.1049 -0.724916)
			(stroke
				(width 0.1)
				(type default)
			)
			(layer "B.Fab")
		)
		(fp_line
			(start 1.1049 0.724916)
			(end -1.1049 0.724916)
			(stroke
				(width 0.1)
				(type default)
			)
			(layer "B.Fab")
		)
		(fp_line
			(start -1.1049 0.724916)
			(end -1.1049 -0.724916)
			(stroke
				(width 0.1)
				(type default)
			)
			(layer "B.Fab")
		)
		(pad "1" smd rect
			(at 0.889 0 90)
			(size 1.016 1.27)
			(layers "B.Cu" "B.Mask" "B.Paste")
			(net "P1V8_PCH_PLL_AUX")
		)
		(pad "2" smd rect
			(at -0.889 0 90)
			(size 1.016 1.27)
			(layers "B.Cu" "B.Mask" "B.Paste")
			(net "GND")
		)
	)
	(footprint ""
		(layer "B.Cu")
		(at 259.37464 -49.430686 180)
		(property "Reference" "PC2341"
			(at 0 0 0)
			(layer "B.SilkS")
			(hide yes)
			(effects
				(font
					(size 1.27 1.27)
				)
				(justify mirror)
			)
		)
		(property "Value" ""
			(at 0 0 0)
			(layer "B.Fab")
			(effects
				(font
					(size 1.27 1.27)
				)
				(justify mirror)
			)
		)
		(duplicate_pad_numbers_are_jumpers no)
		(fp_line
			(start 0.7874 0.4064)
			(end 0.7874 -0.4064)
			(stroke
				(width 0.1524)
				(type default)
			)
			(layer "B.SilkS")
		)
		(fp_line
			(start 0.7874 -0.4064)
			(end -0.7874 -0.4064)
			(stroke
				(width 0.1524)
				(type default)
			)
			(layer "B.SilkS")
		)
		(fp_line
			(start -0.7874 0.4064)
			(end 0.7874 0.4064)
			(stroke
				(width 0.1524)
				(type default)
			)
			(layer "B.SilkS")
		)
		(fp_line
			(start -0.7874 -0.4064)
			(end -0.7874 0.4064)
			(stroke
				(width 0.1524)
				(type default)
			)
			(layer "B.SilkS")
		)
		(fp_line
			(start 0.67945 0.3048)
			(end 0.67945 -0.305054)
			(stroke
				(width 0.1)
				(type default)
			)
			(layer "B.Fab")
		)
		(fp_line
			(start 0.67945 -0.305054)
			(end 0.12065 -0.305054)
			(stroke
				(width 0.1)
				(type default)
			)
			(layer "B.Fab")
		)
		(fp_line
			(start 0.12065 0.3048)
			(end 0.67945 0.3048)
			(stroke
				(width 0.1)
				(type default)
			)
			(layer "B.Fab")
		)
		(fp_line
			(start 0.12065 0.2794)
			(end 0.12065 0.3048)
			(stroke
				(width 0.1)
				(type default)
			)
			(layer "B.Fab")
		)
		(fp_line
			(start 0.12065 -0.2794)
			(end -0.12065 -0.2794)
			(stroke
				(width 0.1)
				(type default)
			)
			(layer "B.Fab")
		)
		(fp_line
			(start 0.12065 -0.305054)
			(end 0.12065 -0.2794)
			(stroke
				(width 0.1)
				(type default)
			)
			(layer "B.Fab")
		)
		(fp_line
			(start -0.120396 0.3048)
			(end -0.120396 0.2794)
			(stroke
				(width 0.1)
				(type default)
			)
			(layer "B.Fab")
		)
		(fp_line
			(start -0.120396 0.2794)
			(end 0.12065 0.2794)
			(stroke
				(width 0.1)
				(type default)
			)
			(layer "B.Fab")
		)
		(fp_line
			(start -0.12065 -0.2794)
			(end -0.12065 -0.3048)
			(stroke
				(width 0.1)
				(type default)
			)
			(layer "B.Fab")
		)
		(fp_line
			(start -0.12065 -0.3048)
			(end -0.67945 -0.3048)
			(stroke
				(width 0.1)
				(type default)
			)
			(layer "B.Fab")
		)
		(fp_line
			(start -0.67945 0.3048)
			(end -0.120396 0.3048)
			(stroke
				(width 0.1)
				(type default)
			)
			(layer "B.Fab")
		)
		(fp_line
			(start -0.67945 -0.3048)
			(end -0.67945 0.3048)
			(stroke
				(width 0.1)
				(type default)
			)
			(layer "B.Fab")
		)
		(pad "1" smd circle
			(at 0.40005 0)
			(size 0 0)
			(layers "B.Cu" "B.Mask" "B.Paste")
			(net "P12V_E1S_ISET_0_R")
		)
		(pad "2" smd circle
			(at -0.40005 0)
			(size 0 0)
			(layers "B.Cu" "B.Mask" "B.Paste")
			(net "GND")
		)
	)
	(footprint ""
		(layer "B.Cu")
		(at 372.613936 -325.098156 -90)
		(property "Reference" "PC310_P0_1"
			(at 0 0 90)
			(layer "B.SilkS")
			(hide yes)
			(effects
				(font
					(size 1.27 1.27)
				)
				(justify mirror)
			)
		)
		(property "Value" ""
			(at 0 0 90)
			(layer "B.Fab")
			(effects
				(font
					(size 1.27 1.27)
				)
				(justify mirror)
			)
		)
		(duplicate_pad_numbers_are_jumpers no)
		(fp_line
			(start -0.7874 0.4064)
			(end 0.7874 0.4064)
			(stroke
				(width 0.1524)
				(type default)
			)
			(layer "B.SilkS")
		)
		(fp_line
			(start 0.7874 0.4064)
			(end 0.7874 -0.4064)
			(stroke
				(width 0.1524)
				(type default)
			)
			(layer "B.SilkS")
		)
		(fp_line
			(start -0.7874 -0.4064)
			(end -0.7874 0.4064)
			(stroke
				(width 0.1524)
				(type default)
			)
			(layer "B.SilkS")
		)
		(fp_line
			(start 0.7874 -0.4064)
			(end -0.7874 -0.4064)
			(stroke
				(width 0.1524)
				(type default)
			)
			(layer "B.SilkS")
		)
		(fp_line
			(start -0.67945 0.3048)
			(end -0.120396 0.3048)
			(stroke
				(width 0.1)
				(type default)
			)
			(layer "B.Fab")
		)
		(fp_line
			(start -0.120396 0.3048)
			(end -0.120396 0.2794)
			(stroke
				(width 0.1)
				(type default)
			)
			(layer "B.Fab")
		)
		(fp_line
			(start 0.12065 0.3048)
			(end 0.67945 0.3048)
			(stroke
				(width 0.1)
				(type default)
			)
			(layer "B.Fab")
		)
		(fp_line
			(start 0.67945 0.3048)
			(end 0.67945 -0.305054)
			(stroke
				(width 0.1)
				(type default)
			)
			(layer "B.Fab")
		)
		(fp_line
			(start -0.120396 0.2794)
			(end 0.12065 0.2794)
			(stroke
				(width 0.1)
				(type default)
			)
			(layer "B.Fab")
		)
		(fp_line
			(start 0.12065 0.2794)
			(end 0.12065 0.3048)
			(stroke
				(width 0.1)
				(type default)
			)
			(layer "B.Fab")
		)
		(fp_line
			(start -0.12065 -0.2794)
			(end -0.12065 -0.3048)
			(stroke
				(width 0.1)
				(type default)
			)
			(layer "B.Fab")
		)
		(fp_line
			(start 0.12065 -0.2794)
			(end -0.12065 -0.2794)
			(stroke
				(width 0.1)
				(type default)
			)
			(layer "B.Fab")
		)
		(fp_line
			(start -0.67945 -0.3048)
			(end -0.67945 0.3048)
			(stroke
				(width 0.1)
				(type default)
			)
			(layer "B.Fab")
		)
		(fp_line
			(start -0.12065 -0.3048)
			(end -0.67945 -0.3048)
			(stroke
				(width 0.1)
				(type default)
			)
			(layer "B.Fab")
		)
		(fp_line
			(start 0.12065 -0.305054)
			(end 0.12065 -0.2794)
			(stroke
				(width 0.1)
				(type default)
			)
			(layer "B.Fab")
		)
		(fp_line
			(start 0.67945 -0.305054)
			(end 0.12065 -0.305054)
			(stroke
				(width 0.1)
				(type default)
			)
			(layer "B.Fab")
		)
		(pad "1" smd circle
			(at 0.40005 0 90)
			(size 0 0)
			(layers "B.Cu" "B.Mask" "B.Paste")
			(net "PVCCIN_CPU0")
		)
		(pad "2" smd circle
			(at -0.40005 0 90)
			(size 0 0)
			(layers "B.Cu" "B.Mask" "B.Paste")
			(net "GND")
		)
	)
)
